# BASEBOARD_FAB2 (Tioga Pass) — schematic netlist excerpt (pin names and nets, part order shuffled) for the footprints in the layout excerpt that follows; sources: Cadence DE-HDL packaged netlist, KiCad conversion of Wiwynn_Tioga_Pass_MB.brd

C2L10  CAP_A  0.01UF 25V 10% X7R  pkg 0402V  page 173 : A = SATA6G_PCH_PCIE_UP_SATA_RXP<1> ; B = SATA6G_P1_RX_C_DP
C9P9  CAP  10UF 16V 10% X6S  pkg 0805  page 208 : A = VR_FET_SW_P12V_STBY_PVCCIN_CPU1 ; B = GND
C2L43  CAP_A  0.01UF 25V 10% X7R  pkg 0402V  page 173 : A = SATA6G_P1_TX_C_DP ; B = SATA6G_PCH_PCIE_UP_SATA_TXP<1>

(kicad_pcb
	(version 20260206)
	(generator "pcbnew")
	(generator_version "10.0")
	(general
		(thickness 1.6)
		(legacy_teardrops no)
	)
	(paper "A4")
	(title_block
		(title "Wiwynn_Tioga_Pass_MB.brd")
		(comment 1 "Tioga Pass / footprints 2727-2729 of 4770")
	)
	(layers
		(0 "F.Cu" signal "TOP")
		(4 "In1.Cu" signal "L2GND")
		(6 "In2.Cu" signal "L3")
		(8 "In3.Cu" signal "L4GND")
		(10 "In4.Cu" signal "L5")
		(12 "In5.Cu" signal "L6GND")
		(14 "In6.Cu" signal "L7VCC")
		(16 "In7.Cu" signal "L8VCC")
		(18 "In8.Cu" signal "L9GND")
		(20 "In9.Cu" signal "L10")
		(22 "In10.Cu" signal "L11GND")
		(24 "In11.Cu" signal "L12")
		(26 "In12.Cu" signal "L13GND")
		(2 "B.Cu" signal "BOTTOM")
		(9 "F.Adhes" user "F.Adhesive")
		(11 "B.Adhes" user "B.Adhesive")
		(13 "F.Paste" user "Package Geometry/Pastemask Top")
		(15 "B.Paste" user "Package Geometry/Pastemask Bottom")
		(5 "F.SilkS" user "Ref Des/Silkscreen Top")
		(7 "B.SilkS" user "Ref Des/Silkscreen Bottom")
		(1 "F.Mask" user "Board Geometry/Soldermask Top")
		(3 "B.Mask" user "Board Geometry/Soldermask Bottom")
		(17 "Dwgs.User" user "User.Drawings")
		(19 "Cmts.User" user "User.Comments")
		(21 "Eco1.User" user "User.Eco1")
		(23 "Eco2.User" user "User.Eco2")
		(25 "Edge.Cuts" user "Board Geometry/Outline")
		(27 "Margin" user)
		(31 "F.CrtYd" user "Package Geometry/Place Bound Top")
		(29 "B.CrtYd" user "Package Geometry/Place Bound Bottom")
		(35 "F.Fab" user "Ref Des/Assembly Top")
		(33 "B.Fab" user "Ref Des/Assembly Bottom")
	)
	(footprint ""
		(layer "B.Cu")
		(at 422.656 -153.035 90)
		(property "Reference" "C2L10"
			(at 0 0 90)
			(layer "B.SilkS")
			(hide yes)
			(effects
				(font
					(size 1.27 1.27)
				)
				(justify mirror)
			)
		)
		(property "Value" ""
			(at 0 0 90)
			(layer "B.Fab")
			(effects
				(font
					(size 1.27 1.27)
				)
				(justify mirror)
			)
		)
		(duplicate_pad_numbers_are_jumpers no)
		(fp_poly
			(pts
				(xy -0.3048 -0.1016) (xy -0.3048 0.9906) (xy 0.3048 0.9906) (xy 0.3048 -0.1016)
			)
			(stroke
				(width 0)
				(type default)
			)
			(fill no)
			(layer "B.CrtYd")
		)
		(fp_line
			(start 0.3048 -0.1016)
			(end 0.3048 0.9906)
			(stroke
				(width 0.1)
				(type default)
			)
			(layer "B.Fab")
		)
		(fp_line
			(start -0.3048 -0.1016)
			(end 0.3048 -0.1016)
			(stroke
				(width 0.1)
				(type default)
			)
			(layer "B.Fab")
		)
		(fp_line
			(start 0.3048 0.9906)
			(end -0.3048 0.9906)
			(stroke
				(width 0.1)
				(type default)
			)
			(layer "B.Fab")
		)
		(fp_line
			(start -0.3048 0.9906)
			(end -0.3048 -0.1016)
			(stroke
				(width 0.1)
				(type default)
			)
			(layer "B.Fab")
		)
		(pad "1" smd rect
			(at 0 0 270)
			(size 0.508 0.508)
			(layers "B.Cu" "B.Mask" "B.Paste")
			(net "SATA6G_PCH_PCIE_UP_SATA_RXP<1>")
		)
		(pad "2" smd rect
			(at 0 0.889 270)
			(size 0.508 0.508)
			(layers "B.Cu" "B.Mask" "B.Paste")
			(net "SATA6G_P1_RX_C_DP")
		)
		(zone
			(layer "B.Cu")
			(hatch none 0.5)
			(connect_pads
				(clearance 0)
			)
			(min_thickness 0.25)
			(keepout
				(tracks allowed)
				(vias not_allowed)
				(pads allowed)
				(copperpour not_allowed)
				(footprints allowed)
			)
			(placement
				(enabled no)
				(sheetname "")
			)
			(fill
				(thermal_gap 0.5)
				(thermal_bridge_width 0.5)
				(island_removal_mode 0)
			)
			(polygon
				(pts
					(xy 422.91 -153.289) (xy 422.91 -152.781) (xy 423.291 -152.781) (xy 423.291 -153.289)
				)
			)
		)
		(zone
			(layer "B.Cu")
			(hatch none 0.5)
			(connect_pads
				(clearance 0)
			)
			(min_thickness 0.25)
			(keepout
				(tracks not_allowed)
				(vias allowed)
				(pads allowed)
				(copperpour not_allowed)
				(footprints allowed)
			)
			(placement
				(enabled no)
				(sheetname "")
			)
			(fill
				(thermal_gap 0.5)
				(thermal_bridge_width 0.5)
				(island_removal_mode 0)
			)
			(polygon
				(pts
					(xy 423.291 -153.289) (xy 423.291 -152.781) (xy 422.91 -152.781) (xy 422.91 -153.289)
				)
			)
		)
	)
	(footprint ""
		(layer "B.Cu")
		(at 32.832802 -76.229464 90)
		(property "Reference" "C9P9"
			(at 0 0 90)
			(layer "B.SilkS")
			(hide yes)
			(effects
				(font
					(size 1.27 1.27)
				)
				(justify mirror)
			)
		)
		(property "Value" ""
			(at 0 0 90)
			(layer "B.Fab")
			(effects
				(font
					(size 1.27 1.27)
				)
				(justify mirror)
			)
		)
		(duplicate_pad_numbers_are_jumpers no)
		(fp_poly
			(pts
				(xy 0.7239 -0.2159) (xy -0.7239 -0.2159) (xy -0.7239 1.9939) (xy 0.7239 1.9939)
			)
			(stroke
				(width 0)
				(type default)
			)
			(fill no)
			(layer "B.CrtYd")
		)
		(fp_line
			(start 0.7239 -0.2159)
			(end 0.7239 1.9939)
			(stroke
				(width 0.1)
				(type default)
			)
			(layer "B.Fab")
		)
		(fp_line
			(start -0.7239 -0.2159)
			(end 0.7239 -0.2159)
			(stroke
				(width 0.1)
				(type default)
			)
			(layer "B.Fab")
		)
		(fp_line
			(start 0.7239 1.9939)
			(end -0.7239 1.9939)
			(stroke
				(width 0.1)
				(type default)
			)
			(layer "B.Fab")
		)
		(fp_line
			(start -0.7239 1.9939)
			(end -0.7239 -0.2159)
			(stroke
				(width 0.1)
				(type default)
			)
			(layer "B.Fab")
		)
		(pad "1" smd rect
			(at 0 0 270)
			(size 1.27 1.016)
			(layers "B.Cu" "B.Mask" "B.Paste")
			(net "VR_FET_SW_P12V_STBY_PVCCIN_CPU1")
		)
		(pad "2" smd rect
			(at 0 1.778 270)
			(size 1.27 1.016)
			(layers "B.Cu" "B.Mask" "B.Paste")
			(net "GND")
		)
		(zone
			(layer "B.Cu")
			(hatch none 0.5)
			(connect_pads
				(clearance 0)
			)
			(min_thickness 0.25)
			(keepout
				(tracks not_allowed)
				(vias allowed)
				(pads allowed)
				(copperpour not_allowed)
				(footprints allowed)
			)
			(placement
				(enabled no)
				(sheetname "")
			)
			(fill
				(thermal_gap 0.5)
				(thermal_bridge_width 0.5)
				(island_removal_mode 0)
			)
			(polygon
				(pts
					(xy 33.340802 -76.864464) (xy 33.340802 -75.594464) (xy 34.102802 -75.594464) (xy 34.102802 -76.864464)
				)
			)
		)
	)
	(footprint ""
		(layer "B.Cu")
		(at 422.402 -141.9606)
		(property "Reference" "C2L43"
			(at 0 0 0)
			(layer "B.SilkS")
			(hide yes)
			(effects
				(font
					(size 1.27 1.27)
				)
				(justify mirror)
			)
		)
		(property "Value" ""
			(at 0 0 0)
			(layer "B.Fab")
			(effects
				(font
					(size 1.27 1.27)
				)
				(justify mirror)
			)
		)
		(duplicate_pad_numbers_are_jumpers no)
		(fp_poly
			(pts
				(xy -0.3048 -0.1016) (xy -0.3048 0.9906) (xy 0.3048 0.9906) (xy 0.3048 -0.1016)
			)
			(stroke
				(width 0)
				(type default)
			)
			(fill no)
			(layer "B.CrtYd")
		)
		(fp_line
			(start -0.3048 -0.1016)
			(end 0.3048 -0.1016)
			(stroke
				(width 0.1)
				(type default)
			)
			(layer "B.Fab")
		)
		(fp_line
			(start -0.3048 0.9906)
			(end -0.3048 -0.1016)
			(stroke
				(width 0.1)
				(type default)
			)
			(layer "B.Fab")
		)
		(fp_line
			(start 0.3048 -0.1016)
			(end 0.3048 0.9906)
			(stroke
				(width 0.1)
				(type default)
			)
			(layer "B.Fab")
		)
		(fp_line
			(start 0.3048 0.9906)
			(end -0.3048 0.9906)
			(stroke
				(width 0.1)
				(type default)
			)
			(layer "B.Fab")
		)
		(pad "1" smd rect
			(at 0 0 180)
			(size 0.508 0.508)
			(layers "B.Cu" "B.Mask" "B.Paste")
			(net "SATA6G_P1_TX_C_DP")
		)
		(pad "2" smd rect
			(at 0 0.889 180)
			(size 0.508 0.508)
			(layers "B.Cu" "B.Mask" "B.Paste")
			(net "SATA6G_PCH_PCIE_UP_SATA_TXP<1>")
		)
		(zone
			(layer "B.Cu")
			(hatch none 0.5)
			(connect_pads
				(clearance 0)
			)
			(min_thickness 0.25)
			(keepout
				(tracks allowed)
				(vias not_allowed)
				(pads allowed)
				(copperpour not_allowed)
				(footprints allowed)
			)
			(placement
				(enabled no)
				(sheetname "")
			)
			(fill
				(thermal_gap 0.5)
				(thermal_bridge_width 0.5)
				(island_removal_mode 0)
			)
			(polygon
				(pts
					(xy 422.656 -141.7066) (xy 422.148 -141.7066) (xy 422.148 -141.3256) (xy 422.656 -141.3256)
				)
			)
		)
		(zone
			(layer "B.Cu")
			(hatch none 0.5)
			(connect_pads
				(clearance 0)
			)
			(min_thickness 0.25)
			(keepout
				(tracks not_allowed)
				(vias allowed)
				(pads allowed)
				(copperpour not_allowed)
				(footprints allowed)
			)
			(placement
				(enabled no)
				(sheetname "")
			)
			(fill
				(thermal_gap 0.5)
				(thermal_bridge_width 0.5)
				(island_removal_mode 0)
			)
			(polygon
				(pts
					(xy 422.656 -141.3256) (xy 422.148 -141.3256) (xy 422.148 -141.7066) (xy 422.656 -141.7066)
				)
			)
		)
	)
)
